# TIMECARD (Time Appliance Project (Time Card)) — schematic netlist excerpt (pin names and nets, part order shuffled) for the footprints in the layout excerpt that follows; sources: Cadence DE-HDL packaged netlist, KiCad conversion of R4006-B0001-02_R01.brd

C221  CAPACITOR  0.1UF 10V 10%  pkg SMC_0402R_H022  page 14 : \1\ = XP3R3V_FPGA ; \2\ = SG
R251  RESISTOR  33.2KOHM 1%  pkg SMC_0402R_H016  page 29 : \1\ = XP1R0V_AGND ; \2\ = XP1R0V_FB_R_TO_AGND

(kicad_pcb
	(version 20260206)
	(generator "pcbnew")
	(generator_version "10.0")
	(general
		(thickness 1.6)
		(legacy_teardrops no)
	)
	(paper "A4")
	(title_block
		(title "timecard-production-celestica-r4006 — R4006-B0001-02_R01.brd")
		(comment 1 "Time Appliance Project (Time Card) / footprints 789-790 of 1113")
	)
	(layers
		(0 "F.Cu" signal "TOP")
		(4 "In1.Cu" signal "L02_GND1")
		(6 "In2.Cu" signal "L03_SIG1")
		(8 "In3.Cu" signal "L04_GND2")
		(10 "In4.Cu" signal "L05_VCC1")
		(12 "In5.Cu" signal "L06_VCC2")
		(14 "In6.Cu" signal "L07_GND3")
		(16 "In7.Cu" signal "L08_SIG2")
		(18 "In8.Cu" signal "L09_GND4")
		(2 "B.Cu" signal "BOTTOM")
		(9 "F.Adhes" user "F.Adhesive")
		(11 "B.Adhes" user "B.Adhesive")
		(13 "F.Paste" user "Package Geometry/Pastemask Top")
		(15 "B.Paste" user "Package Geometry/Pastemask Bottom")
		(5 "F.SilkS" user "Ref Des/Silkscreen Top")
		(7 "B.SilkS" user "Ref Des/Silkscreen Bottom")
		(1 "F.Mask" user "Board Geometry/Soldermask Top")
		(3 "B.Mask" user "Board Geometry/Soldermask Bottom")
		(17 "Dwgs.User" user "User.Drawings")
		(19 "Cmts.User" user "User.Comments")
		(21 "Eco1.User" user "User.Eco1")
		(23 "Eco2.User" user "User.Eco2")
		(25 "Edge.Cuts" user "Board Geometry/Outline")
		(27 "Margin" user)
		(31 "F.CrtYd" user "Package Geometry/Place Bound Top")
		(29 "B.CrtYd" user "Package Geometry/Place Bound Bottom")
		(35 "F.Fab" user "Ref Des/Assembly Top")
		(33 "B.Fab" user "Ref Des/Assembly Bottom")
	)
	(footprint ""
		(layer "B.Cu")
		(at 146.1516 -59.563 90)
		(property "Reference" "R251"
			(at 0.889 2.78003 270)
			(unlocked yes)
			(layer "B.SilkS")
			(effects
				(font
					(size 0.7874 0.5842)
					(thickness 0.1524)
				)
				(justify mirror)
			)
		)
		(property "Value" "VAL*"
			(at -0.02032 2.13233 90)
			(unlocked yes)
			(layer "B.Fab")
			(hide yes)
			(effects
				(font
					(size 0.7874 0.5842)
					(thickness 0.1524)
				)
				(justify mirror)
			)
		)
		(property "Tolerance" "TOL*"
			(at -0.044704 3.05435 90)
			(unlocked yes)
			(layer "Cmts.User")
			(hide yes)
			(effects
				(font
					(size 0.7874 0.5842)
					(thickness 0.1524)
				)
				(justify mirror)
			)
		)
		(property "User Part Number" "PARTNUM*"
			(at -0.02032 4.024884 90)
			(unlocked yes)
			(layer "Cmts.User")
			(hide yes)
			(effects
				(font
					(size 0.7874 0.5842)
					(thickness 0.1524)
				)
				(justify mirror)
			)
		)
		(property "Device Type" "RESISTOR-G155-03322-01,33.2KOHA"
			(at -0.008382 1.210564 90)
			(unlocked yes)
			(layer "B.Fab")
			(hide yes)
			(effects
				(font
					(size 0.7874 0.5842)
					(thickness 0.1524)
				)
				(justify mirror)
			)
		)
		(duplicate_pad_numbers_are_jumpers no)
		(fp_line
			(start 1.143 -0.5588)
			(end 1.143 0.5588)
			(stroke
				(width 0.1)
				(type default)
			)
			(layer "B.SilkS")
		)
		(fp_line
			(start -1.143 -0.5588)
			(end 1.143 -0.5588)
			(stroke
				(width 0.1)
				(type default)
			)
			(layer "B.SilkS")
		)
		(fp_line
			(start 1.143 0.5588)
			(end -1.143 0.5588)
			(stroke
				(width 0.1)
				(type default)
			)
			(layer "B.SilkS")
		)
		(fp_line
			(start -1.143 0.5588)
			(end -1.143 -0.5588)
			(stroke
				(width 0.1)
				(type default)
			)
			(layer "B.SilkS")
		)
		(fp_poly
			(pts
				(xy 1.143 0.5588) (xy -1.143 0.5588) (xy -1.143 -0.5588) (xy 1.143 -0.5588)
			)
			(stroke
				(width 0)
				(type default)
			)
			(fill no)
			(layer "B.CrtYd")
		)
		(fp_line
			(start 0.508 -0.3048)
			(end 0.508 0.3048)
			(stroke
				(width 0.1)
				(type default)
			)
			(layer "B.Fab")
		)
		(fp_line
			(start -0.508 -0.3048)
			(end 0.508 -0.3048)
			(stroke
				(width 0.1)
				(type default)
			)
			(layer "B.Fab")
		)
		(fp_line
			(start 0.508 0.3048)
			(end -0.508 0.3048)
			(stroke
				(width 0.1)
				(type default)
			)
			(layer "B.Fab")
		)
		(fp_line
			(start -0.508 0.3048)
			(end -0.508 -0.3048)
			(stroke
				(width 0.1)
				(type default)
			)
			(layer "B.Fab")
		)
		(pad "1" smd rect
			(at 0.5334 0 270)
			(size 0.7112 0.6096)
			(layers "B.Cu" "B.Mask" "B.Paste")
			(net "XP1R0V_AGND")
		)
		(pad "2" smd rect
			(at -0.5334 0 270)
			(size 0.7112 0.6096)
			(layers "B.Cu" "B.Mask" "B.Paste")
			(net "XP1R0V_FB_R_TO_AGND")
		)
		(zone
			(layer "B.Cu")
			(hatch none 0.5)
			(connect_pads
				(clearance 0)
			)
			(min_thickness 0.25)
			(keepout
				(tracks allowed)
				(vias not_allowed)
				(pads allowed)
				(copperpour not_allowed)
				(footprints allowed)
			)
			(placement
				(enabled no)
				(sheetname "")
			)
			(fill
				(thermal_gap 0.5)
				(thermal_bridge_width 0.5)
				(island_removal_mode 0)
			)
			(polygon
				(pts
					(xy 146.4564 -59.6392) (xy 145.8468 -59.6392) (xy 145.8468 -59.4868) (xy 146.4564 -59.4868)
				)
			)
		)
		(zone
			(layer "B.Cu")
			(hatch none 0.5)
			(connect_pads
				(clearance 0)
			)
			(min_thickness 0.25)
			(keepout
				(tracks not_allowed)
				(vias allowed)
				(pads allowed)
				(copperpour not_allowed)
				(footprints allowed)
			)
			(placement
				(enabled no)
				(sheetname "")
			)
			(fill
				(thermal_gap 0.5)
				(thermal_bridge_width 0.5)
				(island_removal_mode 0)
			)
			(polygon
				(pts
					(xy 146.4564 -59.6392) (xy 145.8468 -59.6392) (xy 145.8468 -59.4868) (xy 146.4564 -59.4868)
				)
			)
		)
	)
	(footprint ""
		(layer "B.Cu")
		(at 106.847132 -47.323248 -90)
		(property "Reference" "C221"
			(at -1.444752 -0.944118 270)
			(unlocked yes)
			(layer "B.SilkS")
			(effects
				(font
					(size 0.635 0.4064)
					(thickness 0.1524)
				)
				(justify mirror)
			)
		)
		(property "Value" "VAL*"
			(at 0 3.718306 270)
			(unlocked yes)
			(layer "B.Fab")
			(hide yes)
			(effects
				(font
					(size 0.7874 0.5842)
					(thickness 0.127)
				)
				(justify mirror)
			)
		)
		(property "Tolerance" "TOL*"
			(at 0 4.861306 270)
			(unlocked yes)
			(layer "Cmts.User")
			(hide yes)
			(effects
				(font
					(size 0.7874 0.5842)
					(thickness 0.127)
				)
				(justify mirror)
			)
		)
		(property "User Part Number" "PARTNUM*"
			(at 0 2.575306 270)
			(unlocked yes)
			(layer "Cmts.User")
			(hide yes)
			(effects
				(font
					(size 0.7874 0.5842)
					(thickness 0.127)
				)
				(justify mirror)
			)
		)
		(property "Device Type" "CAPACITOR-G105-0B104-CK,0.1UF,A"
			(at 0 1.432306 270)
			(unlocked yes)
			(layer "B.Fab")
			(hide yes)
			(effects
				(font
					(size 0.7874 0.5842)
					(thickness 0.127)
				)
				(justify mirror)
			)
		)
		(duplicate_pad_numbers_are_jumpers no)
		(fp_line
			(start -0.970026 0.4699)
			(end 0.970026 0.4699)
			(stroke
				(width 0.1)
				(type default)
			)
			(layer "B.SilkS")
		)
		(fp_line
			(start 0.970026 0.4699)
			(end 0.970026 -0.4699)
			(stroke
				(width 0.1)
				(type default)
			)
			(layer "B.SilkS")
		)
		(fp_line
			(start -0.970026 -0.4699)
			(end -0.970026 0.4699)
			(stroke
				(width 0.1)
				(type default)
			)
			(layer "B.SilkS")
		)
		(fp_line
			(start 0.970026 -0.4699)
			(end -0.970026 -0.4699)
			(stroke
				(width 0.1)
				(type default)
			)
			(layer "B.SilkS")
		)
		(fp_poly
			(pts
				(xy 0.970026 0.4699) (xy -0.970026 0.4699) (xy -0.970026 -0.4699) (xy 0.970026 -0.4699)
			)
			(stroke
				(width 0)
				(type default)
			)
			(fill no)
			(layer "B.CrtYd")
		)
		(fp_line
			(start -0.508 0.3048)
			(end 0.508 0.3048)
			(stroke
				(width 0.1)
				(type default)
			)
			(layer "B.Fab")
		)
		(fp_line
			(start 0.508 0.3048)
			(end 0.508 -0.3048)
			(stroke
				(width 0.1)
				(type default)
			)
			(layer "B.Fab")
		)
		(fp_line
			(start -0.508 -0.3048)
			(end -0.508 0.3048)
			(stroke
				(width 0.1)
				(type default)
			)
			(layer "B.Fab")
		)
		(fp_line
			(start 0.508 -0.3048)
			(end -0.508 -0.3048)
			(stroke
				(width 0.1)
				(type default)
			)
			(layer "B.Fab")
		)
		(pad "1" smd circle
			(at 0.500126 0 90)
			(size 0.635 0.635)
			(layers "B.Cu" "B.Mask" "B.Paste")
			(net "XP3R3V_FPGA")
		)
		(pad "2" smd circle
			(at -0.500126 0 90)
			(size 0.635 0.635)
			(layers "B.Cu" "B.Mask" "B.Paste")
			(net "SG")
		)
	)
)
